# TIMECARD (Time Appliance Project (Time Card)) — schematic netlist excerpt (pin names and nets, part order shuffled) for the footprints in the layout excerpt that follows; sources: Cadence DE-HDL packaged netlist, KiCad conversion of R4006-B0001-02_R01.brd

U35  LM75BDP_TSSOP8  pkg SOP8_118_P0256_V2  page 17
  SDA  = R_LM75B_2_I2C_SDA
  SCL  = LM75B_I2C_SCL
  OS  = FPGA_IN_LM75B_INT2_N
  GND  = SG
  A2  = UNNAMED_6_LM75BDPTSSOP8_I59_A2
  A1  = UNNAMED_6_LM75BDPTSSOP8_I59_A1
  A0  = UNNAMED_6_LM75BDPTSSOP8_I59_A0
  VCC  = XP3R3V_FPGA

TP181  TP_PIONT  pkg TP010CT020B030_PTH  page 25 : \1\ = IO_L21P_16

(kicad_pcb
	(version 20260206)
	(generator "pcbnew")
	(generator_version "10.0")
	(general
		(thickness 1.6)
		(legacy_teardrops no)
	)
	(paper "A4")
	(title_block
		(title "timecard-production-celestica-r4006 — R4006-B0001-02_R01.brd")
		(comment 1 "Time Appliance Project (Time Card) / footprints 53-54 of 1113")
	)
	(layers
		(0 "F.Cu" signal "TOP")
		(4 "In1.Cu" signal "L02_GND1")
		(6 "In2.Cu" signal "L03_SIG1")
		(8 "In3.Cu" signal "L04_GND2")
		(10 "In4.Cu" signal "L05_VCC1")
		(12 "In5.Cu" signal "L06_VCC2")
		(14 "In6.Cu" signal "L07_GND3")
		(16 "In7.Cu" signal "L08_SIG2")
		(18 "In8.Cu" signal "L09_GND4")
		(2 "B.Cu" signal "BOTTOM")
		(9 "F.Adhes" user "F.Adhesive")
		(11 "B.Adhes" user "B.Adhesive")
		(13 "F.Paste" user "Package Geometry/Pastemask Top")
		(15 "B.Paste" user "Package Geometry/Pastemask Bottom")
		(5 "F.SilkS" user "Ref Des/Silkscreen Top")
		(7 "B.SilkS" user "Ref Des/Silkscreen Bottom")
		(1 "F.Mask" user "Board Geometry/Soldermask Top")
		(3 "B.Mask" user "Board Geometry/Soldermask Bottom")
		(17 "Dwgs.User" user "User.Drawings")
		(19 "Cmts.User" user "User.Comments")
		(21 "Eco1.User" user "User.Eco1")
		(23 "Eco2.User" user "User.Eco2")
		(25 "Edge.Cuts" user "Board Geometry/Outline")
		(27 "Margin" user)
		(31 "F.CrtYd" user "Package Geometry/Place Bound Top")
		(29 "B.CrtYd" user "Package Geometry/Place Bound Bottom")
		(35 "F.Fab" user "Ref Des/Assembly Top")
		(33 "B.Fab" user "Ref Des/Assembly Bottom")
	)
	(footprint ""
		(layer "F.Cu")
		(at 54.229 -80.645 -90)
		(property "Reference" "U35"
			(at 0.508 -2.70637 90)
			(unlocked yes)
			(layer "F.SilkS")
			(effects
				(font
					(size 0.7874 0.5842)
					(thickness 0.1524)
				)
			)
		)
		(property "Value" ""
			(at 0 0 270)
			(layer "F.Fab")
			(effects
				(font
					(size 1.27 1.27)
				)
			)
		)
		(property "Device Type" "LM75BDP_TSSOP8-G220-10215-01"
			(at -0.03175 2.55651 270)
			(unlocked yes)
			(layer "F.Fab")
			(hide yes)
			(effects
				(font
					(size 0.7874 0.5842)
					(thickness 0.1524)
				)
			)
		)
		(property "User Part Number" "PARTNUM*"
			(at -0.037592 3.488182 270)
			(unlocked yes)
			(layer "Cmts.User")
			(hide yes)
			(effects
				(font
					(size 0.7874 0.5842)
					(thickness 0.1524)
				)
			)
		)
		(duplicate_pad_numbers_are_jumpers no)
		(fp_line
			(start -1.778 1.778)
			(end 1.778 1.778)
			(stroke
				(width 0.1)
				(type default)
			)
			(layer "F.SilkS")
		)
		(fp_line
			(start 1.778 1.778)
			(end 1.778 1.45796)
			(stroke
				(width 0.1)
				(type default)
			)
			(layer "F.SilkS")
		)
		(fp_line
			(start -3.3147 1.45796)
			(end -1.778 1.45796)
			(stroke
				(width 0.1)
				(type default)
			)
			(layer "F.SilkS")
		)
		(fp_line
			(start -1.778 1.45796)
			(end -1.778 1.778)
			(stroke
				(width 0.1)
				(type default)
			)
			(layer "F.SilkS")
		)
		(fp_line
			(start 1.778 1.45796)
			(end 3.3147 1.45796)
			(stroke
				(width 0.1)
				(type default)
			)
			(layer "F.SilkS")
		)
		(fp_line
			(start 3.3147 1.45796)
			(end 3.3147 -1.45796)
			(stroke
				(width 0.1)
				(type default)
			)
			(layer "F.SilkS")
		)
		(fp_line
			(start -3.3147 -1.45796)
			(end -3.3147 1.45796)
			(stroke
				(width 0.1)
				(type default)
			)
			(layer "F.SilkS")
		)
		(fp_line
			(start -1.778 -1.45796)
			(end -3.3147 -1.45796)
			(stroke
				(width 0.1)
				(type default)
			)
			(layer "F.SilkS")
		)
		(fp_line
			(start 1.778 -1.45796)
			(end 1.778 -1.778)
			(stroke
				(width 0.1)
				(type default)
			)
			(layer "F.SilkS")
		)
		(fp_line
			(start 3.3147 -1.45796)
			(end 1.778 -1.45796)
			(stroke
				(width 0.1)
				(type default)
			)
			(layer "F.SilkS")
		)
		(fp_line
			(start -1.778 -1.778)
			(end -1.778 -1.45796)
			(stroke
				(width 0.1)
				(type default)
			)
			(layer "F.SilkS")
		)
		(fp_line
			(start 1.778 -1.778)
			(end -1.778 -1.778)
			(stroke
				(width 0.1)
				(type default)
			)
			(layer "F.SilkS")
		)
		(fp_poly
			(pts
				(arc
					(start -3.730498 -1.372362)
					(mid -3.730498 -0.610362)
					(end -3.730498 -1.372362)
				)
			)
			(stroke
				(width 0)
				(type default)
			)
			(fill yes)
			(layer "F.SilkS")
		)
		(fp_poly
			(pts
				(xy -3.5687 -2.032) (xy -3.5687 2.032) (xy 3.5687 2.032) (xy 3.5687 -2.032)
			)
			(stroke
				(width 0)
				(type default)
			)
			(fill no)
			(layer "F.CrtYd")
		)
		(fp_line
			(start -1.524 1.524)
			(end -1.524 -1.524)
			(stroke
				(width 0.1)
				(type default)
			)
			(layer "F.Fab")
		)
		(fp_line
			(start 1.524 1.524)
			(end -1.524 1.524)
			(stroke
				(width 0.1)
				(type default)
			)
			(layer "F.Fab")
		)
		(fp_line
			(start -1.524 -1.524)
			(end 1.524 -1.524)
			(stroke
				(width 0.1)
				(type default)
			)
			(layer "F.Fab")
		)
		(fp_line
			(start 1.524 -1.524)
			(end 1.524 1.524)
			(stroke
				(width 0.1)
				(type default)
			)
			(layer "F.Fab")
		)
		(fp_poly
			(pts
				(arc
					(start -0.9906 -1.3208)
					(mid -0.9906 -0.5588)
					(end -0.9906 -1.3208)
				)
			)
			(stroke
				(width 0)
				(type default)
			)
			(fill yes)
			(layer "F.Fab")
		)
		(fp_text user "5"
			(at 3.91795 1.905 0)
			(unlocked yes)
			(layer "F.SilkS")
			(effects
				(font
					(size 0.635 0.4064)
					(thickness 0.1524)
				)
			)
		)
		(fp_text user "4"
			(at -4.08305 1.778 0)
			(unlocked yes)
			(layer "F.SilkS")
			(effects
				(font
					(size 0.635 0.4064)
					(thickness 0.1524)
				)
			)
		)
		(fp_text user "8"
			(at 3.40995 -2.413 0)
			(unlocked yes)
			(layer "F.SilkS")
			(effects
				(font
					(size 0.635 0.4064)
					(thickness 0.1524)
				)
			)
		)
		(fp_text user "5"
			(at 3.21437 1.651 0)
			(unlocked yes)
			(layer "F.Fab")
			(effects
				(font
					(size 0.7874 0.5842)
					(thickness 0.1524)
				)
			)
		)
		(fp_text user "4"
			(at -3.26263 1.524 0)
			(unlocked yes)
			(layer "F.Fab")
			(effects
				(font
					(size 0.7874 0.5842)
					(thickness 0.1524)
				)
			)
		)
		(fp_text user "8"
			(at 3.21437 -1.905 0)
			(unlocked yes)
			(layer "F.Fab")
			(effects
				(font
					(size 0.7874 0.5842)
					(thickness 0.1524)
				)
			)
		)
		(pad "1" smd rect
			(at -2.2987 -0.97536)
			(size 0.4572 1.524)
			(layers "F.Cu" "F.Mask" "F.Paste")
			(net "R_LM75B_2_I2C_SDA")
		)
		(pad "2" smd rect
			(at -2.2987 -0.32512)
			(size 0.4572 1.524)
			(layers "F.Cu" "F.Mask" "F.Paste")
			(net "LM75B_I2C_SCL")
		)
		(pad "3" smd rect
			(at -2.2987 0.32512)
			(size 0.4572 1.524)
			(layers "F.Cu" "F.Mask" "F.Paste")
			(net "FPGA_IN_LM75B_INT2_N")
		)
		(pad "4" smd rect
			(at -2.2987 0.97536)
			(size 0.4572 1.524)
			(layers "F.Cu" "F.Mask" "F.Paste")
			(net "SG")
		)
		(pad "5" smd rect
			(at 2.2987 0.97536)
			(size 0.4572 1.524)
			(layers "F.Cu" "F.Mask" "F.Paste")
			(net "UNNAMED_6_LM75BDPTSSOP8_I59_A2")
		)
		(pad "6" smd rect
			(at 2.2987 0.32512)
			(size 0.4572 1.524)
			(layers "F.Cu" "F.Mask" "F.Paste")
			(net "UNNAMED_6_LM75BDPTSSOP8_I59_A1")
		)
		(pad "7" smd rect
			(at 2.2987 -0.32512)
			(size 0.4572 1.524)
			(layers "F.Cu" "F.Mask" "F.Paste")
			(net "UNNAMED_6_LM75BDPTSSOP8_I59_A0")
		)
		(pad "8" smd rect
			(at 2.2987 -0.97536)
			(size 0.4572 1.524)
			(layers "F.Cu" "F.Mask" "F.Paste")
			(net "XP3R3V_FPGA")
		)
	)
	(footprint ""
		(layer "F.Cu")
		(at 95.25 -53.34)
		(property "Reference" "TP181"
			(at 0 0 0)
			(layer "F.SilkS")
			(hide yes)
			(effects
				(font
					(size 1.27 1.27)
				)
			)
		)
		(property "Value" ""
			(at 0 0 0)
			(layer "F.Fab")
			(effects
				(font
					(size 1.27 1.27)
				)
			)
		)
		(property "Device Type" "TP_PIONT-TP010CT020B030_PTH-TPA"
			(at -1.341882 0.996696 0)
			(unlocked yes)
			(layer "F.Fab")
			(hide yes)
			(effects
				(font
					(size 0.7874 0.5842)
					(thickness 0.1524)
				)
				(justify left)
			)
		)
		(duplicate_pad_numbers_are_jumpers no)
		(fp_poly
			(pts
				(arc
					(start 0.889 0)
					(mid -0.889 0)
					(end 0.889 0)
				)
			)
			(stroke
				(width 0)
				(type default)
			)
			(fill no)
			(layer "B.CrtYd")
		)
		(fp_poly
			(pts
				(arc
					(start 0.889 0)
					(mid -0.889 0)
					(end 0.889 0)
				)
			)
			(stroke
				(width 0)
				(type default)
			)
			(fill no)
			(layer "F.CrtYd")
		)
		(pad "1" thru_hole circle
			(at 0 0)
			(size 0.508 0.508)
			(drill 0.254)
			(layers "*.Cu" "*.Mask")
			(remove_unused_layers no)
			(net "IO_L21P_16")
			(clearance 0.1016)
			(padstack
				(mode front_inner_back)
				(layer "Inner"
					(shape circle)
					(size 0.508 0.508)
					(clearance 0.1016)
				)
				(layer "B.Cu"
					(shape circle)
					(size 0.762 0.762)
					(clearance -0.0254)
				)
			)
		)
	)
)
